# S9S_MB_2U (Grand Teton) — schematic netlist excerpt (pin names and nets, part order shuffled) for the footprints in the layout excerpt that follows; sources: Cadence DE-HDL packaged netlist, KiCad conversion of 03242023_DA0F0TMBIJ0_F0T_Motherboard_J_brd_V01_OCP.brd

U309  PI3EQX1002EZREX  IC  pkg TQFN24_TH_0-35_2-5X2-5  page 169
  EQA  = FM_USB3_1_EQA
  FGA  = FM_USB3_1_FGA
  SWA  = FM_USB3_1_SWA
  EN  = FM_USB3_1_EN_N
  VDD_1  = P3V3_AUX_USB_BUF
  AIP  = USB3_PCH_TX_C_DP<4>
  AIN  = USB3_PCH_TX_C_DN<4>
  GND_1  = GND
  GND_2  = GND
  GND_3  = GND
  BON  = USB3_PCH_RX_BUF_C_DN<4>
  BOP  = USB3_PCH_RX_BUF_C_DP<4>
  RXDET_EN  = FM_USB3_1_RXDET_EN
  SWB  = FM_USB3_1_SWB
  FGB  = FM_USB3_1_FGB
  EQB  = FM_USB3_1_EQB
  VDD_2  = P3V3_AUX_USB_BUF
  BIP  = USB3_PCH_RX_C_DP<4>
  BIN  = USB3_PCH_RX_C_DN<4>
  GND_4  = GND
  GND_5  = GND
  GND_6  = GND
  AON  = USB3_PCH_TX_BUF_DN<4>
  AOP  = USB3_PCH_TX_BUF_DP<4>
  TH_GND  = GND

(kicad_pcb
	(version 20260206)
	(generator "pcbnew")
	(generator_version "10.0")
	(general
		(thickness 1.6)
		(legacy_teardrops no)
	)
	(paper "A4")
	(title_block
		(title "03242023_DA0F0TMBIJ0_F0T_Motherboard_J_brd_V01_OCP.brd")
		(comment 1 "Grand Teton / footprints 4422-4422 of 6105")
	)
	(layers
		(0 "F.Cu" signal "TOP")
		(4 "In1.Cu" signal "GND")
		(6 "In2.Cu" signal "IN1")
		(8 "In3.Cu" signal "GND1")
		(10 "In4.Cu" signal "IN2")
		(12 "In5.Cu" signal "GND2")
		(14 "In6.Cu" signal "IN3")
		(16 "In7.Cu" signal "GND3")
		(18 "In8.Cu" signal "VCC")
		(20 "In9.Cu" signal "VCC1")
		(22 "In10.Cu" signal "GND4")
		(24 "In11.Cu" signal "IN4")
		(26 "In12.Cu" signal "GND5")
		(28 "In13.Cu" signal "IN5")
		(30 "In14.Cu" signal "GND6")
		(32 "In15.Cu" signal "IN6")
		(34 "In16.Cu" signal "GND7")
		(2 "B.Cu" signal "BOTTOM")
		(9 "F.Adhes" user "F.Adhesive")
		(11 "B.Adhes" user "B.Adhesive")
		(13 "F.Paste" user "Package Geometry/Pastemask Top")
		(15 "B.Paste" user "Package Geometry/Pastemask Bottom")
		(5 "F.SilkS" user "Ref Des/Silkscreen Top")
		(7 "B.SilkS" user "Ref Des/Silkscreen Bottom")
		(1 "F.Mask" user "Board Geometry/Soldermask Top")
		(3 "B.Mask" user "Board Geometry/Soldermask Bottom")
		(17 "Dwgs.User" user "User.Drawings")
		(19 "Cmts.User" user "User.Comments")
		(21 "Eco1.User" user "User.Eco1")
		(23 "Eco2.User" user "User.Eco2")
		(25 "Edge.Cuts" user "Board Geometry/Outline")
		(27 "Margin" user)
		(31 "F.CrtYd" user "Package Geometry/Place Bound Top")
		(29 "B.CrtYd" user "Package Geometry/Place Bound Bottom")
		(35 "F.Fab" user "Ref Des/Assembly Top")
		(33 "B.Fab" user "Ref Des/Assembly Bottom")
	)
	(footprint ""
		(layer "B.Cu")
		(at 127.84074 -26.276808 -90)
		(property "Reference" "U309"
			(at 0 0 90)
			(layer "B.SilkS")
			(hide yes)
			(effects
				(font
					(size 1.27 1.27)
				)
				(justify mirror)
			)
		)
		(property "Value" ""
			(at 0 0 90)
			(layer "B.Fab")
			(effects
				(font
					(size 1.27 1.27)
				)
				(justify mirror)
			)
		)
		(duplicate_pad_numbers_are_jumpers no)
		(fp_line
			(start -1.618742 1.618742)
			(end -1.17856 1.618742)
			(stroke
				(width 0.1524)
				(type default)
			)
			(layer "B.SilkS")
		)
		(fp_line
			(start -0.42418 1.618742)
			(end 0.37592 1.618742)
			(stroke
				(width 0.1524)
				(type default)
			)
			(layer "B.SilkS")
		)
		(fp_line
			(start 1.32588 1.618742)
			(end 1.618742 1.618742)
			(stroke
				(width 0.1524)
				(type default)
			)
			(layer "B.SilkS")
		)
		(fp_line
			(start 1.618742 1.618742)
			(end 1.618742 -1.618742)
			(stroke
				(width 0.1524)
				(type default)
			)
			(layer "B.SilkS")
		)
		(fp_line
			(start -1.618742 -1.618742)
			(end -1.618742 1.618742)
			(stroke
				(width 0.1524)
				(type default)
			)
			(layer "B.SilkS")
		)
		(fp_line
			(start -1.27 -1.618742)
			(end -1.618742 -1.618742)
			(stroke
				(width 0.1524)
				(type default)
			)
			(layer "B.SilkS")
		)
		(fp_line
			(start 0.42164 -1.618742)
			(end -0.29464 -1.618742)
			(stroke
				(width 0.1524)
				(type default)
			)
			(layer "B.SilkS")
		)
		(fp_line
			(start 1.618742 -1.618742)
			(end 1.52146 -1.618742)
			(stroke
				(width 0.1524)
				(type default)
			)
			(layer "B.SilkS")
		)
		(fp_poly
			(pts
				(xy 2.663952 -1.172972) (xy 1.855724 -0.903478) (xy 2.124964 -1.711706)
			)
			(stroke
				(width 0)
				(type default)
			)
			(fill yes)
			(layer "B.SilkS")
		)
		(fp_line
			(start -1.27508 1.27508)
			(end -1.27508 -1.27508)
			(stroke
				(width 0.1)
				(type default)
			)
			(layer "B.Fab")
		)
		(fp_line
			(start 1.27508 1.27508)
			(end -1.27508 1.27508)
			(stroke
				(width 0.1)
				(type default)
			)
			(layer "B.Fab")
		)
		(fp_line
			(start -1.27508 -1.27508)
			(end 1.27508 -1.27508)
			(stroke
				(width 0.1)
				(type default)
			)
			(layer "B.Fab")
		)
		(fp_line
			(start 1.27508 -1.27508)
			(end 1.27508 1.27508)
			(stroke
				(width 0.1)
				(type default)
			)
			(layer "B.Fab")
		)
		(fp_poly
			(pts
				(xy 2.4892 -1.081024) (xy 2.4892 -0.319024) (xy 1.7272 -0.700024)
			)
			(stroke
				(width 0)
				(type default)
			)
			(fill yes)
			(layer "B.Fab")
		)
		(pad "1" smd rect
			(at 1.225042 -0.700024)
			(size 0.127 0.508)
			(layers "B.Cu" "B.Mask" "B.Paste")
			(net "FM_USB3_1_EQA")
		)
		(pad "2" smd rect
			(at 1.225042 -0.350012)
			(size 0.127 0.508)
			(layers "B.Cu" "B.Mask" "B.Paste")
			(net "FM_USB3_1_FGA")
		)
		(pad "3" smd rect
			(at 1.225042 0)
			(size 0.127 0.508)
			(layers "B.Cu" "B.Mask" "B.Paste")
			(net "FM_USB3_1_SWA")
		)
		(pad "4" smd rect
			(at 1.225042 0.350012)
			(size 0.127 0.508)
			(layers "B.Cu" "B.Mask" "B.Paste")
			(net "FM_USB3_1_EN_N")
		)
		(pad "5" smd rect
			(at 1.225042 0.700024)
			(size 0.127 0.508)
			(layers "B.Cu" "B.Mask" "B.Paste")
			(net "P3V3_AUX_USB_BUF")
		)
		(pad "6" smd rect
			(at 1.050036 1.225042 90)
			(size 0.127 0.508)
			(layers "B.Cu" "B.Mask" "B.Paste")
			(net "USB3_PCH_TX_C_DP<4>")
		)
		(pad "7" smd rect
			(at 0.700024 1.225042 90)
			(size 0.127 0.508)
			(layers "B.Cu" "B.Mask" "B.Paste")
			(net "USB3_PCH_TX_C_DN<4>")
		)
		(pad "8" smd rect
			(at 0.350012 1.225042 90)
			(size 0.127 0.508)
			(layers "B.Cu" "B.Mask" "B.Paste")
			(net "GND")
		)
		(pad "9" smd rect
			(at 0 1.225042 90)
			(size 0.127 0.508)
			(layers "B.Cu" "B.Mask" "B.Paste")
			(net "GND")
		)
		(pad "10" smd rect
			(at -0.350012 1.225042 90)
			(size 0.127 0.508)
			(layers "B.Cu" "B.Mask" "B.Paste")
			(net "GND")
		)
		(pad "11" smd rect
			(at -0.700024 1.225042 90)
			(size 0.127 0.508)
			(layers "B.Cu" "B.Mask" "B.Paste")
			(net "USB3_PCH_RX_BUF_C_DN<4>")
		)
		(pad "12" smd rect
			(at -1.050036 1.225042 90)
			(size 0.127 0.508)
			(layers "B.Cu" "B.Mask" "B.Paste")
			(net "USB3_PCH_RX_BUF_C_DP<4>")
		)
		(pad "13" smd rect
			(at -1.225042 0.700024)
			(size 0.127 0.508)
			(layers "B.Cu" "B.Mask" "B.Paste")
			(net "FM_USB3_1_RXDET_EN")
		)
		(pad "14" smd rect
			(at -1.225042 0.350012)
			(size 0.127 0.508)
			(layers "B.Cu" "B.Mask" "B.Paste")
			(net "FM_USB3_1_SWB")
		)
		(pad "15" smd rect
			(at -1.225042 0)
			(size 0.127 0.508)
			(layers "B.Cu" "B.Mask" "B.Paste")
			(net "FM_USB3_1_FGB")
		)
		(pad "16" smd rect
			(at -1.225042 -0.350012)
			(size 0.127 0.508)
			(layers "B.Cu" "B.Mask" "B.Paste")
			(net "FM_USB3_1_EQB")
		)
		(pad "17" smd rect
			(at -1.225042 -0.700024)
			(size 0.127 0.508)
			(layers "B.Cu" "B.Mask" "B.Paste")
			(net "P3V3_AUX_USB_BUF")
		)
		(pad "18" smd rect
			(at -1.050036 -1.225042 90)
			(size 0.127 0.508)
			(layers "B.Cu" "B.Mask" "B.Paste")
			(net "USB3_PCH_RX_C_DP<4>")
		)
		(pad "19" smd rect
			(at -0.700024 -1.225042 90)
			(size 0.127 0.508)
			(layers "B.Cu" "B.Mask" "B.Paste")
			(net "USB3_PCH_RX_C_DN<4>")
		)
		(pad "20" smd rect
			(at -0.350012 -1.225042 90)
			(size 0.127 0.508)
			(layers "B.Cu" "B.Mask" "B.Paste")
			(net "GND")
		)
		(pad "21" smd rect
			(at 0 -1.225042 90)
			(size 0.127 0.508)
			(layers "B.Cu" "B.Mask" "B.Paste")
			(net "GND")
		)
		(pad "22" smd rect
			(at 0.350012 -1.225042 90)
			(size 0.127 0.508)
			(layers "B.Cu" "B.Mask" "B.Paste")
			(net "GND")
		)
		(pad "23" smd rect
			(at 0.700024 -1.225042 90)
			(size 0.127 0.508)
			(layers "B.Cu" "B.Mask" "B.Paste")
			(net "USB3_PCH_TX_BUF_DN<4>")
		)
		(pad "24" smd rect
			(at 1.050036 -1.225042 90)
			(size 0.127 0.508)
			(layers "B.Cu" "B.Mask" "B.Paste")
			(net "USB3_PCH_TX_BUF_DP<4>")
		)
		(pad "TH" smd rect
			(at 0 0 90)
			(size 1.4224 1.4224)
			(layers "B.Cu" "B.Mask" "B.Paste")
			(net "GND")
		)
	)
)
